# BASEBOARD_FAB2 (Tioga Pass) — schematic netlist excerpt (pin names and nets, part order shuffled) for the footprints in the layout excerpt that follows; sources: Cadence DE-HDL packaged netlist, KiCad conversion of Wiwynn_Tioga_Pass_MB.brd

C2G4  CAP_A  47UF 4V 20% X5R  pkg 0603V  page 225 : A = PVDDQ_GHJ ; B = GND
RT16  1R3F-GP  1%  pkg RCL_GP  page 207 : \1\ = VR_PVCCIN_CPU1_PHASE1_RC ; \2\ = GND

(kicad_pcb
	(version 20260206)
	(generator "pcbnew")
	(generator_version "10.0")
	(general
		(thickness 1.6)
		(legacy_teardrops no)
	)
	(paper "A4")
	(title_block
		(title "Wiwynn_Tioga_Pass_MB.brd")
		(comment 1 "Tioga Pass / footprints 1846-1848 of 4770")
	)
	(layers
		(0 "F.Cu" signal "TOP")
		(4 "In1.Cu" signal "L2GND")
		(6 "In2.Cu" signal "L3")
		(8 "In3.Cu" signal "L4GND")
		(10 "In4.Cu" signal "L5")
		(12 "In5.Cu" signal "L6GND")
		(14 "In6.Cu" signal "L7VCC")
		(16 "In7.Cu" signal "L8VCC")
		(18 "In8.Cu" signal "L9GND")
		(20 "In9.Cu" signal "L10")
		(22 "In10.Cu" signal "L11GND")
		(24 "In11.Cu" signal "L12")
		(26 "In12.Cu" signal "L13GND")
		(2 "B.Cu" signal "BOTTOM")
		(9 "F.Adhes" user "F.Adhesive")
		(11 "B.Adhes" user "B.Adhesive")
		(13 "F.Paste" user "Package Geometry/Pastemask Top")
		(15 "B.Paste" user "Package Geometry/Pastemask Bottom")
		(5 "F.SilkS" user "Ref Des/Silkscreen Top")
		(7 "B.SilkS" user "Ref Des/Silkscreen Bottom")
		(1 "F.Mask" user "Board Geometry/Soldermask Top")
		(3 "B.Mask" user "Board Geometry/Soldermask Bottom")
		(17 "Dwgs.User" user "User.Drawings")
		(19 "Cmts.User" user "User.Comments")
		(21 "Eco1.User" user "User.Eco1")
		(23 "Eco2.User" user "User.Eco2")
		(25 "Edge.Cuts" user "Board Geometry/Outline")
		(27 "Margin" user)
		(31 "F.CrtYd" user "Package Geometry/Place Bound Top")
		(29 "B.CrtYd" user "Package Geometry/Place Bound Bottom")
		(35 "F.Fab" user "Ref Des/Assembly Top")
		(33 "B.Fab" user "Ref Des/Assembly Bottom")
	)
	(footprint ""
		(layer "F.Cu")
		(at 35.7886 -52.9082 -90)
		(property "Reference" "RT16"
			(at 0 0 270)
			(layer "F.SilkS")
			(hide yes)
			(effects
				(font
					(size 1.27 1.27)
				)
			)
		)
		(property "Value" "*"
			(at -0.0254 -2.6289 270)
			(unlocked yes)
			(layer "F.Fab")
			(hide yes)
			(effects
				(font
					(size 1.27 1.016)
					(thickness 0.1524)
				)
			)
		)
		(property "Device Type" "1R3F-GP_RCL_GP-1R3F-GP,64.1R00A"
			(at -0.0254 -4.1529 270)
			(unlocked yes)
			(layer "F.Fab")
			(hide yes)
			(effects
				(font
					(size 1.27 1.016)
					(thickness 0.1524)
				)
			)
		)
		(duplicate_pad_numbers_are_jumpers no)
		(fp_line
			(start -0.4826 0)
			(end -0.2032 0)
			(stroke
				(width 0.2032)
				(type default)
			)
			(layer "F.SilkS")
		)
		(fp_line
			(start 0.2032 0)
			(end 0.4826 0)
			(stroke
				(width 0.2032)
				(type default)
			)
			(layer "F.SilkS")
		)
		(fp_rect
			(start -0.5842 1.3335)
			(end 0.5842 -1.3335)
			(stroke
				(width 0)
				(type default)
			)
			(fill no)
			(layer "F.CrtYd")
		)
		(fp_rect
			(start -0.5842 1.3335)
			(end 0.5842 -1.3335)
			(stroke
				(width 0)
				(type default)
			)
			(fill no)
			(layer "F.Fab")
		)
		(pad "1" smd custom
			(at 0 -0.762 270)
			(size 0.2159 0.2159)
			(layers "F.Cu" "F.Mask" "F.Paste")
			(net "VR_PVCCIN_CPU1_PHASE1_RC")
			(options
				(clearance outline)
				(anchor circle)
			)
			(primitives
				(gr_poly
					(pts
						(arc
							(start -0.3302 -0.4318)
							(mid -0.402042 -0.402042)
							(end -0.4318 -0.3302)
						)
						(arc
							(start -0.4318 0.3302)
							(mid -0.402042 0.402042)
							(end -0.3302 0.4318)
						)
						(arc
							(start 0.3302 0.4318)
							(mid 0.402042 0.402042)
							(end 0.4318 0.3302)
						)
						(arc
							(start 0.4318 -0.3302)
							(mid 0.402042 -0.402042)
							(end 0.3302 -0.4318)
						)
					)
					(width 0)
					(fill yes)
				)
			)
		)
		(pad "2" smd custom
			(at 0 0.762 270)
			(size 0.2159 0.2159)
			(layers "F.Cu" "F.Mask" "F.Paste")
			(net "GND")
			(options
				(clearance outline)
				(anchor circle)
			)
			(primitives
				(gr_poly
					(pts
						(arc
							(start -0.3302 -0.4318)
							(mid -0.402042 -0.402042)
							(end -0.4318 -0.3302)
						)
						(arc
							(start -0.4318 0.3302)
							(mid -0.402042 0.402042)
							(end -0.3302 0.4318)
						)
						(arc
							(start 0.3302 0.4318)
							(mid 0.402042 0.402042)
							(end 0.4318 0.3302)
						)
						(arc
							(start 0.4318 -0.3302)
							(mid 0.402042 -0.402042)
							(end 0.3302 -0.4318)
						)
					)
					(width 0)
					(fill yes)
				)
			)
		)
	)
	(footprint ""
		(layer "F.Cu")
		(at 145.415 -26.67)
		(property "Reference" ""
			(at 0 0 0)
			(layer "F.SilkS")
			(hide yes)
			(effects
				(font
					(size 1.27 1.27)
				)
			)
		)
		(property "Value" ""
			(at 0 0 0)
			(layer "F.Fab")
			(effects
				(font
					(size 1.27 1.27)
				)
			)
		)
		(duplicate_pad_numbers_are_jumpers no)
		(fp_poly
			(pts
				(arc
					(start 2.032 0)
					(mid -2.032 0)
					(end 2.032 0)
				)
			)
			(stroke
				(width 0)
				(type default)
			)
			(fill no)
			(layer "F.CrtYd")
		)
		(pad "1" smd circle
			(at 0 0)
			(size 1.016 1.016)
			(layers "F.Cu" "F.Mask" "F.Paste")
			(net "Net_389")
		)
		(zone
			(layer "F.Cu")
			(hatch none 0.5)
			(connect_pads
				(clearance 0)
			)
			(min_thickness 0.25)
			(keepout
				(tracks not_allowed)
				(vias allowed)
				(pads allowed)
				(copperpour not_allowed)
				(footprints allowed)
			)
			(placement
				(enabled no)
				(sheetname "")
			)
			(fill
				(thermal_gap 0.5)
				(thermal_bridge_width 0.5)
				(island_removal_mode 0)
			)
			(polygon
				(pts
					(arc
						(start 146.939 -26.67)
						(mid 143.891 -26.67)
						(end 146.939 -26.67)
					)
				)
			)
		)
		(zone
			(layers "F.Cu" "B.Cu" "In1.Cu" "In2.Cu" "In3.Cu" "In4.Cu" "In5.Cu" "In6.Cu"
				"In7.Cu" "In8.Cu" "In9.Cu" "In10.Cu" "In11.Cu" "In12.Cu"
			)
			(hatch none 0.5)
			(connect_pads
				(clearance 0)
			)
			(min_thickness 0.25)
			(keepout
				(tracks allowed)
				(vias not_allowed)
				(pads allowed)
				(copperpour not_allowed)
				(footprints allowed)
			)
			(placement
				(enabled no)
				(sheetname "")
			)
			(fill
				(thermal_gap 0.5)
				(thermal_bridge_width 0.5)
				(island_removal_mode 0)
			)
			(polygon
				(pts
					(arc
						(start 146.939 -26.67)
						(mid 143.891 -26.67)
						(end 146.939 -26.67)
					)
				)
			)
		)
	)
	(footprint ""
		(layer "F.Cu")
		(at 88.392 -12.954 90)
		(property "Reference" "C2G4"
			(at 1.848866 0.752348 90)
			(unlocked yes)
			(layer "F.SilkS")
			(effects
				(font
					(size 1.27 0.9652)
					(thickness 0.1524)
				)
			)
		)
		(property "Value" ""
			(at 0 0 90)
			(layer "F.Fab")
			(effects
				(font
					(size 1.27 1.27)
				)
			)
		)
		(duplicate_pad_numbers_are_jumpers no)
		(fp_rect
			(start -0.500126 1.598422)
			(end 0.500126 -0.201422)
			(stroke
				(width 0)
				(type default)
			)
			(fill no)
			(layer "F.CrtYd")
		)
		(fp_line
			(start 0.500126 -0.201422)
			(end 0.500126 1.598422)
			(stroke
				(width 0.1)
				(type default)
			)
			(layer "F.Fab")
		)
		(fp_line
			(start -0.500126 -0.201422)
			(end 0.500126 -0.201422)
			(stroke
				(width 0.1)
				(type default)
			)
			(layer "F.Fab")
		)
		(fp_line
			(start 0.500126 1.598422)
			(end -0.500126 1.598422)
			(stroke
				(width 0.1)
				(type default)
			)
			(layer "F.Fab")
		)
		(fp_line
			(start -0.500126 1.598422)
			(end -0.500126 -0.201422)
			(stroke
				(width 0.1)
				(type default)
			)
			(layer "F.Fab")
		)
		(pad "1" smd rect
			(at 0 0)
			(size 0.889 0.9906)
			(layers "F.Cu" "F.Mask" "F.Paste")
			(net "PVDDQ_GHJ")
		)
		(pad "2" smd rect
			(at 0 1.397)
			(size 0.889 0.9906)
			(layers "F.Cu" "F.Mask" "F.Paste")
			(net "GND")
		)
		(zone
			(layer "F.Cu")
			(hatch none 0.5)
			(connect_pads
				(clearance 0)
			)
			(min_thickness 0.25)
			(keepout
				(tracks allowed)
				(vias not_allowed)
				(pads allowed)
				(copperpour not_allowed)
				(footprints allowed)
			)
			(placement
				(enabled no)
				(sheetname "")
			)
			(fill
				(thermal_gap 0.5)
				(thermal_bridge_width 0.5)
				(island_removal_mode 0)
			)
			(polygon
				(pts
					(xy 89.3445 -12.4587) (xy 89.3445 -13.4493) (xy 88.8365 -13.4493) (xy 88.8365 -12.4587)
				)
			)
		)
		(zone
			(layer "F.Cu")
			(hatch none 0.5)
			(connect_pads
				(clearance 0)
			)
			(min_thickness 0.25)
			(keepout
				(tracks not_allowed)
				(vias allowed)
				(pads allowed)
				(copperpour not_allowed)
				(footprints allowed)
			)
			(placement
				(enabled no)
				(sheetname "")
			)
			(fill
				(thermal_gap 0.5)
				(thermal_bridge_width 0.5)
				(island_removal_mode 0)
			)
			(polygon
				(pts
					(xy 89.3445 -12.4587) (xy 89.3445 -13.4493) (xy 88.8365 -13.4493) (xy 88.8365 -12.4587)
				)
			)
		)
	)
)
